# BASEBOARD_FAB2 (Tioga Pass) — schematic netlist excerpt (pin names and nets, part order shuffled) for the footprints in the layout excerpt that follows; sources: Cadence DE-HDL packaged netlist, KiCad conversion of Wiwynn_Tioga_Pass_MB.brd

R8D11  RES  33.2 1% CHIP  pkg 0402  page 121 : A = RMII_PCH_SPRNGVLLE_ARB_OUT ; B = RMII_PCH_SPRNGVLLE_ARB_OUT_R
C7E1  CAP_A  0.1UF 16V 10% X7R  pkg 0402V  page 99 : A = PVCCIO_CPU0 ; B = GND
C3N19  CAP_A  1.0UF 6.3V 10% X6S  pkg 0402V  page 132 : A = PVNN_PCH_STBY ; B = GND

(kicad_pcb
	(version 20260206)
	(generator "pcbnew")
	(generator_version "10.0")
	(general
		(thickness 1.6)
		(legacy_teardrops no)
	)
	(paper "A4")
	(title_block
		(title "Wiwynn_Tioga_Pass_MB.brd")
		(comment 1 "Tioga Pass / footprints 4553-4555 of 4770")
	)
	(layers
		(0 "F.Cu" signal "TOP")
		(4 "In1.Cu" signal "L2GND")
		(6 "In2.Cu" signal "L3")
		(8 "In3.Cu" signal "L4GND")
		(10 "In4.Cu" signal "L5")
		(12 "In5.Cu" signal "L6GND")
		(14 "In6.Cu" signal "L7VCC")
		(16 "In7.Cu" signal "L8VCC")
		(18 "In8.Cu" signal "L9GND")
		(20 "In9.Cu" signal "L10")
		(22 "In10.Cu" signal "L11GND")
		(24 "In11.Cu" signal "L12")
		(26 "In12.Cu" signal "L13GND")
		(2 "B.Cu" signal "BOTTOM")
		(9 "F.Adhes" user "F.Adhesive")
		(11 "B.Adhes" user "B.Adhesive")
		(13 "F.Paste" user "Package Geometry/Pastemask Top")
		(15 "B.Paste" user "Package Geometry/Pastemask Bottom")
		(5 "F.SilkS" user "Ref Des/Silkscreen Top")
		(7 "B.SilkS" user "Ref Des/Silkscreen Bottom")
		(1 "F.Mask" user "Board Geometry/Soldermask Top")
		(3 "B.Mask" user "Board Geometry/Soldermask Bottom")
		(17 "Dwgs.User" user "User.Drawings")
		(19 "Cmts.User" user "User.Comments")
		(21 "Eco1.User" user "User.Eco1")
		(23 "Eco2.User" user "User.Eco2")
		(25 "Edge.Cuts" user "Board Geometry/Outline")
		(27 "Margin" user)
		(31 "F.CrtYd" user "Package Geometry/Place Bound Top")
		(29 "B.CrtYd" user "Package Geometry/Place Bound Bottom")
		(35 "F.Fab" user "Ref Des/Assembly Top")
		(33 "B.Fab" user "Ref Des/Assembly Bottom")
	)
	(footprint ""
		(layer "B.Cu")
		(at 383.73685 -106.25455)
		(property "Reference" "C3N19"
			(at 0 0 0)
			(layer "B.SilkS")
			(hide yes)
			(effects
				(font
					(size 1.27 1.27)
				)
				(justify mirror)
			)
		)
		(property "Value" ""
			(at 0 0 0)
			(layer "B.Fab")
			(effects
				(font
					(size 1.27 1.27)
				)
				(justify mirror)
			)
		)
		(duplicate_pad_numbers_are_jumpers no)
		(fp_rect
			(start 0.2794 0.9144)
			(end -0.2794 -0.1143)
			(stroke
				(width 0)
				(type default)
			)
			(fill no)
			(layer "B.CrtYd")
		)
		(fp_line
			(start -0.2794 -0.1143)
			(end -0.2794 0.9144)
			(stroke
				(width 0.1)
				(type default)
			)
			(layer "B.Fab")
		)
		(fp_line
			(start -0.2794 0.9144)
			(end 0.2794 0.9144)
			(stroke
				(width 0.1)
				(type default)
			)
			(layer "B.Fab")
		)
		(fp_line
			(start 0.2794 -0.1143)
			(end -0.2794 -0.1143)
			(stroke
				(width 0.1)
				(type default)
			)
			(layer "B.Fab")
		)
		(fp_line
			(start 0.2794 0.9144)
			(end 0.2794 -0.1143)
			(stroke
				(width 0.1)
				(type default)
			)
			(layer "B.Fab")
		)
		(pad "1" smd custom
			(at 0 0 270)
			(size 0.10414 0.10414)
			(layers "B.Cu" "B.Mask" "B.Paste")
			(net "PVNN_PCH_STBY")
			(options
				(clearance outline)
				(anchor circle)
			)
			(primitives
				(gr_poly
					(pts
						(xy -0.20828 -0.08636) (xy -0.20828 0.08636) (xy -0.08636 0.20828) (xy 0.086614 0.20828) (xy 0.20828 0.086614)
						(xy 0.20828 -0.08636) (xy 0.08636 -0.20828) (xy -0.08636 -0.20828)
					)
					(width 0)
					(fill yes)
				)
			)
		)
		(pad "2" smd custom
			(at 0 0.8001 270)
			(size 0.10414 0.10414)
			(layers "B.Cu" "B.Mask" "B.Paste")
			(net "GND")
			(options
				(clearance outline)
				(anchor circle)
			)
			(primitives
				(gr_poly
					(pts
						(xy -0.20828 -0.08636) (xy -0.20828 0.08636) (xy -0.08636 0.20828) (xy 0.086614 0.20828) (xy 0.20828 0.086614)
						(xy 0.20828 -0.08636) (xy 0.08636 -0.20828) (xy -0.08636 -0.20828)
					)
					(width 0)
					(fill yes)
				)
			)
		)
		(zone
			(layer "B.Cu")
			(hatch none 0.5)
			(connect_pads
				(clearance 0)
			)
			(min_thickness 0.25)
			(keepout
				(tracks allowed)
				(vias not_allowed)
				(pads allowed)
				(copperpour not_allowed)
				(footprints allowed)
			)
			(placement
				(enabled no)
				(sheetname "")
			)
			(fill
				(thermal_gap 0.5)
				(thermal_bridge_width 0.5)
				(island_removal_mode 0)
			)
			(polygon
				(pts
					(xy 383.82448 -106.045) (xy 383.82448 -105.664) (xy 383.64922 -105.664) (xy 383.648966 -106.045)
				)
			)
		)
		(zone
			(layer "B.Cu")
			(hatch none 0.5)
			(connect_pads
				(clearance 0)
			)
			(min_thickness 0.25)
			(keepout
				(tracks not_allowed)
				(vias allowed)
				(pads allowed)
				(copperpour not_allowed)
				(footprints allowed)
			)
			(placement
				(enabled no)
				(sheetname "")
			)
			(fill
				(thermal_gap 0.5)
				(thermal_bridge_width 0.5)
				(island_removal_mode 0)
			)
			(polygon
				(pts
					(xy 383.82448 -106.045) (xy 383.82448 -105.664) (xy 383.64922 -105.664) (xy 383.648966 -106.045)
				)
			)
		)
	)
	(footprint ""
		(layer "B.Cu")
		(at 326.3519 -124.1298 -90)
		(property "Reference" "C7E1"
			(at 0 0 90)
			(layer "B.SilkS")
			(hide yes)
			(effects
				(font
					(size 1.27 1.27)
				)
				(justify mirror)
			)
		)
		(property "Value" ""
			(at 0 0 90)
			(layer "B.Fab")
			(effects
				(font
					(size 1.27 1.27)
				)
				(justify mirror)
			)
		)
		(duplicate_pad_numbers_are_jumpers no)
		(fp_poly
			(pts
				(xy -0.3048 -0.1016) (xy -0.3048 0.9906) (xy 0.3048 0.9906) (xy 0.3048 -0.1016)
			)
			(stroke
				(width 0)
				(type default)
			)
			(fill no)
			(layer "B.CrtYd")
		)
		(fp_line
			(start -0.3048 0.9906)
			(end -0.3048 -0.1016)
			(stroke
				(width 0.1)
				(type default)
			)
			(layer "B.Fab")
		)
		(fp_line
			(start 0.3048 0.9906)
			(end -0.3048 0.9906)
			(stroke
				(width 0.1)
				(type default)
			)
			(layer "B.Fab")
		)
		(fp_line
			(start -0.3048 -0.1016)
			(end 0.3048 -0.1016)
			(stroke
				(width 0.1)
				(type default)
			)
			(layer "B.Fab")
		)
		(fp_line
			(start 0.3048 -0.1016)
			(end 0.3048 0.9906)
			(stroke
				(width 0.1)
				(type default)
			)
			(layer "B.Fab")
		)
		(pad "1" smd rect
			(at 0 0 90)
			(size 0.508 0.508)
			(layers "B.Cu" "B.Mask" "B.Paste")
			(net "PVCCIO_CPU0")
		)
		(pad "2" smd rect
			(at 0 0.889 90)
			(size 0.508 0.508)
			(layers "B.Cu" "B.Mask" "B.Paste")
			(net "GND")
		)
		(zone
			(layer "B.Cu")
			(hatch none 0.5)
			(connect_pads
				(clearance 0)
			)
			(min_thickness 0.25)
			(keepout
				(tracks not_allowed)
				(vias allowed)
				(pads allowed)
				(copperpour not_allowed)
				(footprints allowed)
			)
			(placement
				(enabled no)
				(sheetname "")
			)
			(fill
				(thermal_gap 0.5)
				(thermal_bridge_width 0.5)
				(island_removal_mode 0)
			)
			(polygon
				(pts
					(xy 325.7169 -123.8758) (xy 325.7169 -124.3838) (xy 326.0979 -124.3838) (xy 326.0979 -123.8758)
				)
			)
		)
		(zone
			(layer "B.Cu")
			(hatch none 0.5)
			(connect_pads
				(clearance 0)
			)
			(min_thickness 0.25)
			(keepout
				(tracks allowed)
				(vias not_allowed)
				(pads allowed)
				(copperpour not_allowed)
				(footprints allowed)
			)
			(placement
				(enabled no)
				(sheetname "")
			)
			(fill
				(thermal_gap 0.5)
				(thermal_bridge_width 0.5)
				(island_removal_mode 0)
			)
			(polygon
				(pts
					(xy 326.0979 -123.8758) (xy 326.0979 -124.3838) (xy 325.7169 -124.3838) (xy 325.7169 -123.8758)
				)
			)
		)
	)
	(footprint ""
		(layer "B.Cu")
		(at 388.366 -87.3125 180)
		(property "Reference" "R8D11"
			(at 0.8382 -0.67818 180)
			(unlocked yes)
			(layer "B.SilkS")
			(effects
				(font
					(size 0.4064 0.254)
					(thickness 0.1524)
				)
				(justify left mirror)
			)
		)
		(property "Value" ""
			(at 0 0 0)
			(layer "B.Fab")
			(effects
				(font
					(size 1.27 1.27)
				)
				(justify mirror)
			)
		)
		(duplicate_pad_numbers_are_jumpers no)
		(fp_poly
			(pts
				(xy 0.2794 -0.1016) (xy -0.2794 -0.1016) (xy -0.2794 0.9906) (xy 0.2794 0.9906)
			)
			(stroke
				(width 0)
				(type default)
			)
			(fill no)
			(layer "B.CrtYd")
		)
		(fp_line
			(start 0.2794 0.9906)
			(end -0.2794 0.9906)
			(stroke
				(width 0.1)
				(type default)
			)
			(layer "B.Fab")
		)
		(fp_line
			(start 0.2794 -0.1016)
			(end 0.2794 0.9906)
			(stroke
				(width 0.1)
				(type default)
			)
			(layer "B.Fab")
		)
		(fp_line
			(start -0.2794 0.9906)
			(end -0.2794 -0.1016)
			(stroke
				(width 0.1)
				(type default)
			)
			(layer "B.Fab")
		)
		(fp_line
			(start -0.2794 -0.1016)
			(end 0.2794 -0.1016)
			(stroke
				(width 0.1)
				(type default)
			)
			(layer "B.Fab")
		)
		(pad "1" smd rect
			(at 0 0)
			(size 0.508 0.508)
			(layers "B.Cu" "B.Mask" "B.Paste")
			(net "RMII_PCH_SPRNGVLLE_ARB_OUT")
		)
		(pad "2" smd rect
			(at 0 0.889)
			(size 0.508 0.508)
			(layers "B.Cu" "B.Mask" "B.Paste")
			(net "RMII_PCH_SPRNGVLLE_ARB_OUT_R")
		)
		(zone
			(layer "B.Cu")
			(hatch none 0.5)
			(connect_pads
				(clearance 0)
			)
			(min_thickness 0.25)
			(keepout
				(tracks not_allowed)
				(vias allowed)
				(pads allowed)
				(copperpour not_allowed)
				(footprints allowed)
			)
			(placement
				(enabled no)
				(sheetname "")
			)
			(fill
				(thermal_gap 0.5)
				(thermal_bridge_width 0.5)
				(island_removal_mode 0)
			)
			(polygon
				(pts
					(xy 388.112 -87.9475) (xy 388.62 -87.9475) (xy 388.62 -87.5665) (xy 388.112 -87.5665)
				)
			)
		)
		(zone
			(layer "B.Cu")
			(hatch none 0.5)
			(connect_pads
				(clearance 0)
			)
			(min_thickness 0.25)
			(keepout
				(tracks allowed)
				(vias not_allowed)
				(pads allowed)
				(copperpour not_allowed)
				(footprints allowed)
			)
			(placement
				(enabled no)
				(sheetname "")
			)
			(fill
				(thermal_gap 0.5)
				(thermal_bridge_width 0.5)
				(island_removal_mode 0)
			)
			(polygon
				(pts
					(xy 388.112 -87.5665) (xy 388.62 -87.5665) (xy 388.62 -87.9475) (xy 388.112 -87.9475)
				)
			)
		)
	)
)
